FILE_TYPE = MULTI_PHYS_TABLE;

PART 'MT25QL128ABA1ESE_SOP8'
CLASS=IC

{========================================================================================}
:CLS_PN          | VALUE                     = JEDEC_TYPE         | ALT_SYMBOLS          | DESCRIPTION                                        | CPN_STATUS ;
{========================================================================================}
 'G221-10224-01' | 'MT25QL128ABA1ESE-0SIT'   = 'SOP8_208_P050_V2' | '(SOP8_208_P050_V2)' | 'IC,FLASH,128MBIT,2.7V-3.6V,SO8W'                  | ''        
 'G221-10301-01' | 'MT25QU128ABA1ESE-0SIT'   = 'SOP8_208_P050_V2' | '(SOP8_208_P050_V2)' | 'IC,SPI FLASH,128MBIT,1.27MM PITCH,1.7V TO 2V,SO8' | ''        

END_PART

END.

